# BASEBOARD_FAB2 (Tioga Pass) — schematic netlist excerpt (pin names and nets, part order shuffled) for the footprints in the layout excerpt that follows; sources: Cadence DE-HDL packaged netlist, KiCad conversion of Wiwynn_Tioga_Pass_MB.brd

EU8F2  ICS9FGP204  IC  pkg MLFP  page 101
  GND(0)  = GND
  VDD96  = P3V3_STBY_MNG
  DOT96SST  = TP_CLK_96M_CKMNG_P
  DOT96SSC  = TP_CLK_96M_CKMNG_N
  OE_96  = PD_CKMNG_OE
  OE_CPU  = PD_CKMNG_OE
  CPUCLKT0  = TP_CLK_100M_R_DP
  CPUCLKC0  = TP_CLK_100M_R_DN
  VDDCPU  = P3V3_STBY_MNG_CPU
  GNDCPU  = GND
  IREF  = A_COMP_CKMNG
  VDD32K  = P3V3_STBY_MNG
  \32khz\  = CLK_32K_SUSCLK_PLD_R
  GND32K  = GND
  VDDREF  = P3V3_STBY_MNG
  \25mhz_0\  = CLK_25M_BMC_R
  \25mhz_1\  = CLK_25M_CPLD_R
  GNDREF  = GND
  X1_25  = XTAL_CK_MNG_IN
  X2_25  = XTAL_CK_MNG_OUT_R
  GND33  = GND
  \33mhz_smbadr\  = PU_33P_33M_SMBADR
  VDD33  = P3V3_STBY_MNG
  RMII(5)  = TP_CLK5_50M_CKMNG
  RMII(4)  = CLK_50M_CKMNG_PCH_10GBE_R
  VDDRMII(0)  = P3V3_STBY_MNG_RMII
  GNDRMII(0)  = GND
  RMII(3)  = CLK_50M_CKMNG_SPRVLLE_R
  RMII(2)  = CLK_50M_CKMNG_BMC_2_R
  GNDRMII(1)  = GND
  VDDRMII(1)  = P3V3_STBY_MNG_RMII
  RMII(1)  = CLK_50M_CKMNG_BMC_1_R
  RMII(0)  = CLK_50M_CKMNG_OCP_R
  VDD_RGMII  = P3V3_STBY_MNG_RGMII
  GND_RGMII  = GND
  RGMII(1)  = TP_CLK_125M
  RGMII(0)  = TP_CLK_125M_BMCA
  SMBCLK  = SMB_HOST_STBY_LVC3_SCL_R4
  SMBDAT  = SMB_HOST_STBY_LVC3_SDA_R4
  VTTPWR_GD_PD_N  = PWRGD_P3V3_STBY
  GND(1)  = GND

(kicad_pcb
	(version 20260206)
	(generator "pcbnew")
	(generator_version "10.0")
	(general
		(thickness 1.6)
		(legacy_teardrops no)
	)
	(paper "A4")
	(title_block
		(title "Wiwynn_Tioga_Pass_MB.brd")
		(comment 1 "Tioga Pass / footprint 997 of 4770 (EU8F2), pads 18-34 of 41")
	)
	(layers
		(0 "F.Cu" signal "TOP")
		(4 "In1.Cu" signal "L2GND")
		(6 "In2.Cu" signal "L3")
		(8 "In3.Cu" signal "L4GND")
		(10 "In4.Cu" signal "L5")
		(12 "In5.Cu" signal "L6GND")
		(14 "In6.Cu" signal "L7VCC")
		(16 "In7.Cu" signal "L8VCC")
		(18 "In8.Cu" signal "L9GND")
		(20 "In9.Cu" signal "L10")
		(22 "In10.Cu" signal "L11GND")
		(24 "In11.Cu" signal "L12")
		(26 "In12.Cu" signal "L13GND")
		(2 "B.Cu" signal "BOTTOM")
		(9 "F.Adhes" user "F.Adhesive")
		(11 "B.Adhes" user "B.Adhesive")
		(13 "F.Paste" user "Package Geometry/Pastemask Top")
		(15 "B.Paste" user "Package Geometry/Pastemask Bottom")
		(5 "F.SilkS" user "Ref Des/Silkscreen Top")
		(7 "B.SilkS" user "Ref Des/Silkscreen Bottom")
		(1 "F.Mask" user "Board Geometry/Soldermask Top")
		(3 "B.Mask" user "Board Geometry/Soldermask Bottom")
		(17 "Dwgs.User" user "User.Drawings")
		(19 "Cmts.User" user "User.Comments")
		(21 "Eco1.User" user "User.Eco1")
		(23 "Eco2.User" user "User.Eco2")
		(25 "Edge.Cuts" user "Board Geometry/Outline")
		(27 "Margin" user)
		(31 "F.CrtYd" user "Package Geometry/Place Bound Top")
		(29 "B.CrtYd" user "Package Geometry/Place Bound Bottom")
		(35 "F.Fab" user "Ref Des/Assembly Top")
		(33 "B.Fab" user "Ref Des/Assembly Bottom")
	)
	(footprint ""
		(layer "F.Cu")
		(at 475.64802 -27.7495 90)
		(property "Reference" "EU8F2"
			(at 8.88365 7.29996 180)
			(unlocked yes)
			(layer "F.SilkS")
			(effects
				(font
					(size 0.7874 0.5842)
					(thickness 0.1524)
				)
			)
		)
		(property "Value" ""
			(at 0 0 90)
			(layer "F.Fab")
			(effects
				(font
					(size 1.27 1.27)
				)
			)
		)
		(duplicate_pad_numbers_are_jumpers no)
		(pad "18" smd custom
			(at 4.36118 5.36448 90)
			(size 0.0762 0.0762)
			(layers "F.Cu" "F.Mask" "F.Paste")
			(net "GND")
			(options
				(clearance outline)
				(anchor circle)
			)
			(primitives
				(gr_poly
					(pts
						(xy -0.1524 0.5715)
						(arc
							(start -0.1524 -0.4191)
							(mid 0 -0.5715)
							(end 0.1524 -0.4191)
						)
						(xy 0.1524 0.5715)
					)
					(width 0)
					(fill yes)
				)
			)
		)
		(pad "19" smd custom
			(at 4.86156 5.36448 90)
			(size 0.0762 0.0762)
			(layers "F.Cu" "F.Mask" "F.Paste")
			(net "XTAL_CK_MNG_IN")
			(options
				(clearance outline)
				(anchor circle)
			)
			(primitives
				(gr_poly
					(pts
						(xy -0.1524 0.5715)
						(arc
							(start -0.1524 -0.4191)
							(mid 0 -0.5715)
							(end 0.1524 -0.4191)
						)
						(xy 0.1524 0.5715)
					)
					(width 0)
					(fill yes)
				)
			)
		)
		(pad "20" smd custom
			(at 5.36194 5.36448 90)
			(size 0.0762 0.0762)
			(layers "F.Cu" "F.Mask" "F.Paste")
			(net "XTAL_CK_MNG_OUT_R")
			(options
				(clearance outline)
				(anchor circle)
			)
			(primitives
				(gr_poly
					(pts
						(xy -0.1524 0.5715)
						(arc
							(start -0.1524 -0.4191)
							(mid 0 -0.5715)
							(end 0.1524 -0.4191)
						)
						(xy 0.1524 0.5715)
					)
					(width 0)
					(fill yes)
				)
			)
		)
		(pad "21" smd custom
			(at 6.223 4.50342 90)
			(size 0.0762 0.0762)
			(layers "F.Cu" "F.Mask" "F.Paste")
			(net "GND")
			(options
				(clearance outline)
				(anchor circle)
			)
			(primitives
				(gr_poly
					(pts
						(xy 0.5715 0.1524)
						(arc
							(start -0.4191 0.1524)
							(mid -0.5715 0)
							(end -0.4191 -0.1524)
						)
						(xy 0.5715 -0.1524)
					)
					(width 0)
					(fill yes)
				)
			)
		)
		(pad "22" smd custom
			(at 6.223 4.00304 90)
			(size 0.0762 0.0762)
			(layers "F.Cu" "F.Mask" "F.Paste")
			(net "PU_33P_33M_SMBADR")
			(options
				(clearance outline)
				(anchor circle)
			)
			(primitives
				(gr_poly
					(pts
						(xy 0.5715 0.1524)
						(arc
							(start -0.4191 0.1524)
							(mid -0.5715 0)
							(end -0.4191 -0.1524)
						)
						(xy 0.5715 -0.1524)
					)
					(width 0)
					(fill yes)
				)
			)
		)
		(pad "23" smd custom
			(at 6.223 3.50266 90)
			(size 0.0762 0.0762)
			(layers "F.Cu" "F.Mask" "F.Paste")
			(net "P3V3_STBY_MNG")
			(options
				(clearance outline)
				(anchor circle)
			)
			(primitives
				(gr_poly
					(pts
						(xy 0.5715 0.1524)
						(arc
							(start -0.4191 0.1524)
							(mid -0.5715 0)
							(end -0.4191 -0.1524)
						)
						(xy 0.5715 -0.1524)
					)
					(width 0)
					(fill yes)
				)
			)
		)
		(pad "24" smd custom
			(at 6.223 3.00228 90)
			(size 0.0762 0.0762)
			(layers "F.Cu" "F.Mask" "F.Paste")
			(net "TP_CLK5_50M_CKMNG")
			(options
				(clearance outline)
				(anchor circle)
			)
			(primitives
				(gr_poly
					(pts
						(xy 0.5715 0.1524)
						(arc
							(start -0.4191 0.1524)
							(mid -0.5715 0)
							(end -0.4191 -0.1524)
						)
						(xy 0.5715 -0.1524)
					)
					(width 0)
					(fill yes)
				)
			)
		)
		(pad "25" smd custom
			(at 6.223 2.5019 90)
			(size 0.0762 0.0762)
			(layers "F.Cu" "F.Mask" "F.Paste")
			(net "CLK_50M_CKMNG_PCH_10GBE_R")
			(options
				(clearance outline)
				(anchor circle)
			)
			(primitives
				(gr_poly
					(pts
						(xy 0.5715 0.1524)
						(arc
							(start -0.4191 0.1524)
							(mid -0.5715 0)
							(end -0.4191 -0.1524)
						)
						(xy 0.5715 -0.1524)
					)
					(width 0)
					(fill yes)
				)
			)
		)
		(pad "26" smd custom
			(at 6.223 2.00152 90)
			(size 0.0762 0.0762)
			(layers "F.Cu" "F.Mask" "F.Paste")
			(net "P3V3_STBY_MNG_RMII")
			(options
				(clearance outline)
				(anchor circle)
			)
			(primitives
				(gr_poly
					(pts
						(xy 0.5715 0.1524)
						(arc
							(start -0.4191 0.1524)
							(mid -0.5715 0)
							(end -0.4191 -0.1524)
						)
						(xy 0.5715 -0.1524)
					)
					(width 0)
					(fill yes)
				)
			)
		)
		(pad "27" smd custom
			(at 6.223 1.50114 90)
			(size 0.0762 0.0762)
			(layers "F.Cu" "F.Mask" "F.Paste")
			(net "GND")
			(options
				(clearance outline)
				(anchor circle)
			)
			(primitives
				(gr_poly
					(pts
						(xy 0.5715 0.1524)
						(arc
							(start -0.4191 0.1524)
							(mid -0.5715 0)
							(end -0.4191 -0.1524)
						)
						(xy 0.5715 -0.1524)
					)
					(width 0)
					(fill yes)
				)
			)
		)
		(pad "28" smd custom
			(at 6.223 1.00076 90)
			(size 0.0762 0.0762)
			(layers "F.Cu" "F.Mask" "F.Paste")
			(net "CLK_50M_CKMNG_SPRVLLE_R")
			(options
				(clearance outline)
				(anchor circle)
			)
			(primitives
				(gr_poly
					(pts
						(xy 0.5715 0.1524)
						(arc
							(start -0.4191 0.1524)
							(mid -0.5715 0)
							(end -0.4191 -0.1524)
						)
						(xy 0.5715 -0.1524)
					)
					(width 0)
					(fill yes)
				)
			)
		)
		(pad "29" smd custom
			(at 6.223 0.50038 90)
			(size 0.0762 0.0762)
			(layers "F.Cu" "F.Mask" "F.Paste")
			(net "CLK_50M_CKMNG_BMC_2_R")
			(options
				(clearance outline)
				(anchor circle)
			)
			(primitives
				(gr_poly
					(pts
						(xy 0.5715 0.1524)
						(arc
							(start -0.4191 0.1524)
							(mid -0.5715 0)
							(end -0.4191 -0.1524)
						)
						(xy 0.5715 -0.1524)
					)
					(width 0)
					(fill yes)
				)
			)
		)
		(pad "30" smd custom
			(at 6.223 0 90)
			(size 0.0762 0.0762)
			(layers "F.Cu" "F.Mask" "F.Paste")
			(net "GND")
			(options
				(clearance outline)
				(anchor circle)
			)
			(primitives
				(gr_poly
					(pts
						(xy 0.5715 0.1524)
						(arc
							(start -0.4191 0.1524)
							(mid -0.5715 0)
							(end -0.4191 -0.1524)
						)
						(xy 0.5715 -0.1524)
					)
					(width 0)
					(fill yes)
				)
			)
		)
		(pad "31" smd custom
			(at 5.36194 -0.85852 90)
			(size 0.0762 0.0762)
			(layers "F.Cu" "F.Mask" "F.Paste")
			(net "P3V3_STBY_MNG_RMII")
			(options
				(clearance outline)
				(anchor circle)
			)
			(primitives
				(gr_poly
					(pts
						(xy 0.1524 -0.5715)
						(arc
							(start 0.1524 0.4191)
							(mid 0 0.5715)
							(end -0.1524 0.4191)
						)
						(xy -0.1524 -0.5715)
					)
					(width 0)
					(fill yes)
				)
			)
		)
		(pad "32" smd custom
			(at 4.86156 -0.85852 90)
			(size 0.0762 0.0762)
			(layers "F.Cu" "F.Mask" "F.Paste")
			(net "CLK_50M_CKMNG_BMC_1_R")
			(options
				(clearance outline)
				(anchor circle)
			)
			(primitives
				(gr_poly
					(pts
						(xy 0.1524 -0.5715)
						(arc
							(start 0.1524 0.4191)
							(mid 0 0.5715)
							(end -0.1524 0.4191)
						)
						(xy -0.1524 -0.5715)
					)
					(width 0)
					(fill yes)
				)
			)
		)
		(pad "33" smd custom
			(at 4.36118 -0.85852 90)
			(size 0.0762 0.0762)
			(layers "F.Cu" "F.Mask" "F.Paste")
			(net "CLK_50M_CKMNG_OCP_R")
			(options
				(clearance outline)
				(anchor circle)
			)
			(primitives
				(gr_poly
					(pts
						(xy 0.1524 -0.5715)
						(arc
							(start 0.1524 0.4191)
							(mid 0 0.5715)
							(end -0.1524 0.4191)
						)
						(xy -0.1524 -0.5715)
					)
					(width 0)
					(fill yes)
				)
			)
		)
		(pad "34" smd custom
			(at 3.8608 -0.85852 90)
			(size 0.0762 0.0762)
			(layers "F.Cu" "F.Mask" "F.Paste")
			(net "P3V3_STBY_MNG_RGMII")
			(options
				(clearance outline)
				(anchor circle)
			)
			(primitives
				(gr_poly
					(pts
						(xy 0.1524 -0.5715)
						(arc
							(start 0.1524 0.4191)
							(mid 0 0.5715)
							(end -0.1524 0.4191)
						)
						(xy -0.1524 -0.5715)
					)
					(width 0)
					(fill yes)
				)
			)
		)
	)
)
